FILE_TYPE = CONNECTIVITY;
{Allegro Design Entry HDL 16.6-p007 (v16-6-112F) 10/10/2012}
"PAGE_NUMBER" = 71;
0"NC";
1"PVCCIN_CPU1\g";
2"PVCCIN_CPU1\g";
3"PVCCIN_CPU1\g";
4"PVCCIN_CPU1\g";
5"GND\g";
6"PVCCIN_CPU1\g";
7"PVCCIO_CPU1\g";
8"VSENSE_VCCINR2PMAX_CPU1";
9"VSENSE_PMAX_CPU1";
10"VSENSE_PVCCIN_CPU1_SKT_VSEN";
11"VSENSE_PVCCIN_CPU1_SKT_VRTN";
%"PVCCIN_CPU1"
"1","(-5425,4425)","0","mstr_symbols","I35";
;
VOLTAGE"2.0V"
CDS_LIB"mstr_symbols"
BODY_TYPE"PLUMBING"
HDL_POWER"PVCCIN_CPU1";
"G\NAC"1;
%"PVCCIN_CPU1"
"1","(-7325,4400)","0","mstr_symbols","I36";
;
VOLTAGE"2.0V"
CDS_LIB"mstr_symbols"
BODY_TYPE"PLUMBING"
HDL_POWER"PVCCIN_CPU1";
"G\NAC"2;
%"PVCCIN_CPU1"
"1","(-3600,4400)","0","mstr_symbols","I40";
;
VOLTAGE"2.0V"
CDS_LIB"mstr_symbols"
BODY_TYPE"PLUMBING"
HDL_POWER"PVCCIN_CPU1";
"G\NAC"3;
%"PVCCIN_CPU1"
"1","(-1725,4375)","0","mstr_symbols","I41";
;
VOLTAGE"2.0V"
BODY_TYPE"PLUMBING"
CDS_LIB"mstr_symbols"
HDL_POWER"PVCCIN_CPU1";
"G\NAC"4;
%"GND"
"1","(-500,525)","0","mstr_symbols","I42";
;
BODY_TYPE"PLUMBING"
VOLTAGE"0.0V"
SIZE"1B"
CDS_LIB"mstr_symbols"
HDL_POWER"GND";
"A\NAC"5;
%"RES"
"2","(-500,750)","0","mstr_discrete","I43";
;
CDS_SEC"1"
PACK_TYPE"0402"
MATERIAL"CHIP"
WATTAGE"1/16W"
LOCATION"R3D27"
VALUE"249"
TOLERANCE"0.1%"
PART_NUMBER"G85996-031"
CDS_LIB"mstr_discrete"
CDS_LOCATION"R3D27"
ROOM"CPU1"
SEC"1"
BOM_COST"PROC_SOCKET"
SEC_TYPE"0402";
"A"
$PN"1"9;
"B"
$PN"2"5;
%"PVCCIN_CPU1"
"1","(-1100,1700)","0","mstr_symbols","I45";
;
HDL_POWER"PVCCIN_CPU1"
BODY_TYPE"PLUMBING"
CDS_LIB"mstr_symbols"
VOLTAGE"2.0V";
"G\NAC"6;
%"RES"
"2","(-1100,1400)","0","mstr_discrete","I49";
;
CDS_SEC"1"
WATTAGE"1/10W"
MATERIAL"CHIP"
PACK_TYPE"0603"
TOLERANCE"1%"
VALUE"100.0K"
PART_NUMBER"G22026-050"
LOCATION"RT8P1"
CDS_LIB"mstr_discrete"
ROOM"CPU1"
CDS_LOCATION"RT8P1"
SEC"1"
SEC_TYPE"0603"
BOM_COST"PROC_SOCKET";
"A"
$PN"1"6;
"B"
$PN"2"8;
%"SKX_EXT_B"
"18","(-6375,2525)","0","chpset_lib","I50";
;
CDS_SEC"18"
PART_NUMBER"TBD"
LOCATION"U2D1"
MATERIAL"IC"
CDS_LIB"chpset_lib"
CDS_LOCATION"U2D1"
SEC"18"
SEC_TYPE"BGA1"
PACK_TYPE"BGA1";
"VCCIN<130>"
$PN"BN78"1;
"VCCIN<131>"
$PN"BN76"1;
"VCCIN<132>"
$PN"BN74"1;
"VCCIN<133>"
$PN"BN72"1;
"VCCIN<134>"
$PN"BN70"1;
"VCCIN<135>"
$PN"BN68"1;
"VCCIN<136>"
$PN"BN66"1;
"VCCIN<137>"
$PN"BN64"1;
"VCCIN<138>"
$PN"BN62"1;
"VCCIN<139>"
$PN"BN60"1;
"VCCIN<140>"
$PN"BM83"1;
"VCCIN<141>"
$PN"BM81"1;
"VCCIN<142>"
$PN"BM79"1;
"VCCIN<143>"
$PN"BM77"1;
"VCCIN<144>"
$PN"BM75"1;
"VCCIN<145>"
$PN"BM73"1;
"VCCIN<146>"
$PN"BM71"1;
"VCCIN<147>"
$PN"BM69"1;
"VCCIN<148>"
$PN"BM67"1;
"VCCIN<149>"
$PN"BM65"1;
"VCCIN<150>"
$PN"BM63"1;
"VCCIN<151>"
$PN"BM61"1;
"VCCIN<152>"
$PN"BL84"1;
"VCCIN<153>"
$PN"BL62"1;
"VCCIN<154>"
$PN"BL60"1;
"VCCIN<155>"
$PN"BK83"1;
"VCCIN<156>"
$PN"BK81"1;
"VCCIN<157>"
$PN"BK79"1;
"VCCIN<158>"
$PN"BK77"1;
"VCCIN<159>"
$PN"BK75"1;
"VCCIN<160>"
$PN"BK73"1;
"VCCIN<161>"
$PN"BK71"1;
"VCCIN<162>"
$PN"BK69"1;
"VCCIN<163>"
$PN"BK67"1;
"VCCIN<164>"
$PN"BK65"1;
"VCCIN<165>"
$PN"BK63"1;
"VCCIN<166>"
$PN"BK61"1;
"VCCIN<167>"
$PN"BJ84"1;
"VCCIN<168>"
$PN"BJ82"1;
"VCCIN<169>"
$PN"BJ80"1;
"VCCIN<170>"
$PN"BJ78"1;
"VCCIN<171>"
$PN"BJ76"1;
"VCCIN<172>"
$PN"BJ74"1;
"VCCIN<173>"
$PN"BJ72"1;
"VCCIN<174>"
$PN"BJ70"1;
"VCCIN<175>"
$PN"BJ68"1;
"VCCIN<176>"
$PN"BJ66"1;
"VCCIN<177>"
$PN"BJ64"1;
"VCCIN<178>"
$PN"BJ62"1;
"VCCIN<179>"
$PN"BJ60"1;
"VCCIN<180>"
$PN"BH83"1;
"VCCIN<181>"
$PN"BH81"1;
"VCCIN<182>"
$PN"BH79"1;
"VCCIN<183>"
$PN"BH77"1;
"VCCIN<184>"
$PN"BH75"1;
"VCCIN<185>"
$PN"BH73"1;
"VCCIN<186>"
$PN"BH71"1;
"VCCIN<187>"
$PN"BH69"1;
"VCCIN<188>"
$PN"BH67"1;
"VCCIN<189>"
$PN"BH65"1;
"VCCIN<190>"
$PN"BH63"1;
"VCCIN<191>"
$PN"BH61"1;
"VCCIN<192>"
$PN"BG84"1;
"VCCIN<193>"
$PN"BG70"1;
"VCCIN<194>"
$PN"BG68"1;
"VCCIN<195>"
$PN"BG66"1;
"VCCIN<196>"
$PN"BG64"1;
"VCCIN<197>"
$PN"BG62"1;
"VCCIN<198>"
$PN"BG60"1;
"VCCIN<199>"
$PN"BF85"2;
"VCCIN<200>"
$PN"BF83"2;
"VCCIN<201>"
$PN"BF81"2;
"VCCIN<202>"
$PN"BF79"2;
"VCCIN<203>"
$PN"BF77"2;
"VCCIN<204>"
$PN"BF75"2;
"VCCIN<205>"
$PN"BF73"2;
"VCCIN<206>"
$PN"BF61"2;
"VCCIN<207>"
$PN"BE84"2;
"VCCIN<208>"
$PN"BE82"2;
"VCCIN<209>"
$PN"BE80"2;
"VCCIN<210>"
$PN"BE78"2;
"VCCIN<211>"
$PN"BE76"2;
"VCCIN<212>"
$PN"BE74"2;
"VCCIN<213>"
$PN"BE72"2;
"VCCIN<214>"
$PN"BE62"2;
"VCCIN<215>"
$PN"BE60"2;
"VCCIN<216>"
$PN"BD85"2;
"VCCIN<217>"
$PN"BD83"2;
"VCCIN<218>"
$PN"BD81"2;
"VCCIN<219>"
$PN"BD79"2;
"VCCIN<220>"
$PN"BD77"2;
"VCCIN<221>"
$PN"BD75"2;
"VCCIN<222>"
$PN"BD73"2;
"VCCIN<223>"
$PN"BD61"2;
"VCCIN<224>"
$PN"BC84"2;
"VCCIN<225>"
$PN"BC62"2;
"VCCIN<226>"
$PN"BC60"2;
"VCCIN<227>"
$PN"BB85"2;
"VCCIN<228>"
$PN"BB61"2;
"VCCIN<229>"
$PN"BA60"2;
"VCCIN<230>"
$PN"AY61"2;
"VCCIN<231>"
$PN"AW60"2;
"VCCIN<232>"
$PN"AV61"2;
"VCCIN<233>"
$PN"AV59"2;
"VCCIN<234>"
$PN"AU60"2;
"VCCIN<235>"
$PN"AU58"2;
"VCCIN<236>"
$PN"AT59"2;
"VCCIN<237>"
$PN"AT57"2;
"VCCIN<238>"
$PN"AR58"2;
"VCCIN<239>"
$PN"AR56"2;
"VCCIN<240>"
$PN"AP57"2;
"VCCIN<241>"
$PN"AP55"2;
"VCCIN<242>"
$PN"AN56"2;
"VCCIN<243>"
$PN"AN54"2;
"VCCIN<244>"
$PN"AN32"2;
"VCCIN<245>"
$PN"AM55"2;
"VCCIN<246>"
$PN"AM53"2;
"VCCIN<247>"
$PN"AM33"2;
"VCCIN<248>"
$PN"AL54"2;
"VCCIN<249>"
$PN"AL52"2;
"VCCIN<250>"
$PN"AL50"2;
"VCCIN<251>"
$PN"AL48"2;
"VCCIN<252>"
$PN"AL46"2;
"VCCIN<253>"
$PN"AL34"2;
"VCCIN<254>"
$PN"AK53"2;
"VCCIN<255>"
$PN"AK51"2;
"VCCIN<256>"
$PN"AK49"2;
"VCCIN<257>"
$PN"AK47"2;
"VCCIN<258>"
$PN"AK45"2;
"VCCIN<259>"
$PN"AK35"2;
"VCCIN<260>"
$PN"AJ36"2;
"VCCIN<261>"
$PN"AH41"2;
"VCCIN<262>"
$PN"AH39"2;
"VCCIN<263>"
$PN"AH37"2;
"VCCIN<264>"
$PN"AG42"2;
"VCCIN<265>"
$PN"AG40"2;
"VCCIN<266>"
$PN"AG38"2;
"VCCIN<267>"
$PN"AF43"2;
%"SKX_EXT_B"
"19","(-2675,2525)","0","chpset_lib","I51";
;
CDS_SEC"19"
PART_NUMBER"TBD"
MATERIAL"IC"
LOCATION"U2D1"
CDS_LIB"chpset_lib"
CDS_LOCATION"U2D1"
SEC"19"
SEC_TYPE"BGA1"
PACK_TYPE"BGA1";
"VSS_VCCIN_SENSE"
$PN"AY85"11;
"VSENSEPMAX"
$PN"AD41"9;
"VCCIN_SENSE"
$PN"BA86"10;
"VCCINPMAX<0>"
$PN"AW86"8;
"VCCINPMAX<1>"
$PN"AV85"8;
"VCCIN<0>"
$PN"CY49"4;
"VCCIN<1>"
$PN"CY47"4;
"VCCIN<2>"
$PN"CW50"4;
"VCCIN<3>"
$PN"CW48"4;
"VCCIN<4>"
$PN"CW46"4;
"VCCIN<5>"
$PN"CV51"4;
"VCCIN<6>"
$PN"CU54"4;
"VCCIN<7>"
$PN"CU52"4;
"VCCIN<8>"
$PN"CU42"4;
"VCCIN<9>"
$PN"CU40"4;
"VCCIN<10>"
$PN"CU38"4;
"VCCIN<11>"
$PN"CT55"4;
"VCCIN<12>"
$PN"CT53"4;
"VCCIN<13>"
$PN"CT41"4;
"VCCIN<14>"
$PN"CT39"4;
"VCCIN<15>"
$PN"CT37"4;
"VCCIN<16>"
$PN"CR56"4;
"VCCIN<17>"
$PN"CR54"4;
"VCCIN<18>"
$PN"CR34"4;
"VCCIN<19>"
$PN"CP57"4;
"VCCIN<20>"
$PN"CP55"4;
"VCCIN<21>"
$PN"CP33"4;
"VCCIN<22>"
$PN"CN58"4;
"VCCIN<23>"
$PN"CN56"4;
"VCCIN<24>"
$PN"CM59"4;
"VCCIN<25>"
$PN"CM57"4;
"VCCIN<26>"
$PN"CL60"4;
"VCCIN<27>"
$PN"CL58"4;
"VCCIN<28>"
$PN"CK61"4;
"VCCIN<29>"
$PN"CK59"4;
"VCCIN<30>"
$PN"CJ60"4;
"VCCIN<31>"
$PN"CH85"4;
"VCCIN<32>"
$PN"CH61"4;
"VCCIN<33>"
$PN"CG84"4;
"VCCIN<34>"
$PN"CG60"4;
"VCCIN<35>"
$PN"CF85"4;
"VCCIN<36>"
$PN"CF61"4;
"VCCIN<37>"
$PN"CE84"4;
"VCCIN<38>"
$PN"CE60"4;
"VCCIN<39>"
$PN"CD85"4;
"VCCIN<40>"
$PN"CD83"4;
"VCCIN<41>"
$PN"CD61"4;
"VCCIN<42>"
$PN"CC84"4;
"VCCIN<43>"
$PN"CC62"4;
"VCCIN<44>"
$PN"CC60"4;
"VCCIN<45>"
$PN"CB83"4;
"VCCIN<46>"
$PN"CB81"4;
"VCCIN<47>"
$PN"CB79"4;
"VCCIN<48>"
$PN"CB77"4;
"VCCIN<49>"
$PN"CB75"4;
"VCCIN<50>"
$PN"CB73"4;
"VCCIN<51>"
$PN"CB61"4;
"VCCIN<52>"
$PN"CA84"4;
"VCCIN<53>"
$PN"CA82"4;
"VCCIN<54>"
$PN"CA80"4;
"VCCIN<55>"
$PN"CA78"4;
"VCCIN<56>"
$PN"CA76"4;
"VCCIN<57>"
$PN"CA74"4;
"VCCIN<58>"
$PN"CA72"4;
"VCCIN<59>"
$PN"CA62"4;
"VCCIN<60>"
$PN"CA60"4;
"VCCIN<61>"
$PN"BY83"3;
"VCCIN<62>"
$PN"BY81"3;
"VCCIN<63>"
$PN"BY79"3;
"VCCIN<64>"
$PN"BY77"3;
"VCCIN<65>"
$PN"BY75"3;
"VCCIN<66>"
$PN"BY73"3;
"VCCIN<67>"
$PN"BY61"3;
"VCCIN<68>"
$PN"BW84"3;
"VCCIN<69>"
$PN"BW70"3;
"VCCIN<70>"
$PN"BW68"3;
"VCCIN<71>"
$PN"BW66"3;
"VCCIN<72>"
$PN"BW64"3;
"VCCIN<73>"
$PN"BW62"3;
"VCCIN<74>"
$PN"BW60"3;
"VCCIN<75>"
$PN"BV83"3;
"VCCIN<76>"
$PN"BV81"3;
"VCCIN<77>"
$PN"BV79"3;
"VCCIN<78>"
$PN"BV77"3;
"VCCIN<79>"
$PN"BV75"3;
"VCCIN<80>"
$PN"BV73"3;
"VCCIN<81>"
$PN"BV71"3;
"VCCIN<82>"
$PN"BV69"3;
"VCCIN<83>"
$PN"BV67"3;
"VCCIN<84>"
$PN"BV65"3;
"VCCIN<85>"
$PN"BV63"3;
"VCCIN<86>"
$PN"BV61"3;
"VCCIN<87>"
$PN"BU84"3;
"VCCIN<88>"
$PN"BU82"3;
"VCCIN<89>"
$PN"BU80"3;
"VCCIN<90>"
$PN"BU78"3;
"VCCIN<91>"
$PN"BU76"3;
"VCCIN<92>"
$PN"BU74"3;
"VCCIN<93>"
$PN"BU72"3;
"VCCIN<94>"
$PN"BU70"3;
"VCCIN<95>"
$PN"BU68"3;
"VCCIN<96>"
$PN"BU66"3;
"VCCIN<97>"
$PN"BU64"3;
"VCCIN<98>"
$PN"BU62"3;
"VCCIN<99>"
$PN"BU60"3;
"VCCIN<100>"
$PN"BT83"3;
"VCCIN<101>"
$PN"BT81"3;
"VCCIN<102>"
$PN"BT79"3;
"VCCIN<103>"
$PN"BT77"3;
"VCCIN<104>"
$PN"BT75"3;
"VCCIN<105>"
$PN"BT73"3;
"VCCIN<106>"
$PN"BT71"3;
"VCCIN<107>"
$PN"BT69"3;
"VCCIN<108>"
$PN"BT67"3;
"VCCIN<109>"
$PN"BT65"3;
"VCCIN<110>"
$PN"BT63"3;
"VCCIN<111>"
$PN"BT61"3;
"VCCIN<112>"
$PN"BR84"3;
"VCCIN<113>"
$PN"BR62"3;
"VCCIN<114>"
$PN"BR60"3;
"VCCIN<115>"
$PN"BP83"3;
"VCCIN<116>"
$PN"BP81"3;
"VCCIN<117>"
$PN"BP79"3;
"VCCIN<118>"
$PN"BP77"3;
"VCCIN<119>"
$PN"BP75"3;
"VCCIN<120>"
$PN"BP73"3;
"VCCIN<121>"
$PN"BP71"3;
"VCCIN<122>"
$PN"BP69"3;
"VCCIN<123>"
$PN"BP67"3;
"VCCIN<124>"
$PN"BP65"3;
"VCCIN<125>"
$PN"BP63"3;
"VCCIN<126>"
$PN"BP61"3;
"VCCIN<127>"
$PN"BN84"3;
"VCCIN<128>"
$PN"BN82"3;
"VCCIN<129>"
$PN"BN80"3;
%"PVCCIO_CPU1"
"1","(-500,1500)","0","mstr_symbols","I52";
;
BODY_TYPE"PLUMBING"
VOLTAGE"1.1V"
CDS_LIB"mstr_symbols"
HDL_POWER"PVCCIO_CPU1";
"G\NAC"7;
%"RES"
"2","(-500,1200)","0","mstr_discrete","I53";
;
CDS_SEC"1"
CDS_LOCATION"R3D32"
TOLERANCE"1%"
WATTAGE"1/16W"
PACK_TYPE"0402"
MATERIAL"EMPTY"
VALUE"10.0"
LOCATION"R3D32"
PART_NUMBER"G21796-066"
CDS_LIB"mstr_discrete"
ROOM"CPU1"
SEC"1"
SEC_TYPE"0402";
"A"
$PN"1"7;
"B"
$PN"2"9;
END.
